(kicad_pcb
	(version 20260206)
	(generator "pcbnew")
	(generator_version "10.0")
	(general
		(thickness 1.6)
		(legacy_teardrops no)
	)
	(paper "A4")
	(title_block
		(title "04192023_DAF0TMB3IC0_F0TG_MB_C_brd_V02_OCP.brd")
		(comment 1 "Grand Teton / footprints 5567-5572 of 8354")
	)
	(layers
		(0 "F.Cu" signal "TOP")
		(4 "In1.Cu" signal "GND")
		(6 "In2.Cu" signal "IN1")
		(8 "In3.Cu" signal "GND1")
		(10 "In4.Cu" signal "IN2")
		(12 "In5.Cu" signal "GND2")
		(14 "In6.Cu" signal "IN3")
		(16 "In7.Cu" signal "GND3")
		(18 "In8.Cu" signal "VCC")
		(20 "In9.Cu" signal "VCC1")
		(22 "In10.Cu" signal "GND4")
		(24 "In11.Cu" signal "IN4")
		(26 "In12.Cu" signal "GND5")
		(28 "In13.Cu" signal "IN5")
		(30 "In14.Cu" signal "GND6")
		(32 "In15.Cu" signal "IN6")
		(34 "In16.Cu" signal "GND7")
		(2 "B.Cu" signal "BOTTOM")
		(9 "F.Adhes" user "F.Adhesive")
		(11 "B.Adhes" user "B.Adhesive")
		(13 "F.Paste" user "Package Geometry/Pastemask Top")
		(15 "B.Paste" user "Package Geometry/Pastemask Bottom")
		(5 "F.SilkS" user "Ref Des/Silkscreen Top")
		(7 "B.SilkS" user "Ref Des/Silkscreen Bottom")
		(1 "F.Mask" user "Board Geometry/Soldermask Top")
		(3 "B.Mask" user "Board Geometry/Soldermask Bottom")
		(17 "Dwgs.User" user "User.Drawings")
		(19 "Cmts.User" user "User.Comments")
		(21 "Eco1.User" user "User.Eco1")
		(23 "Eco2.User" user "User.Eco2")
		(25 "Edge.Cuts" user "Board Geometry/Outline")
		(27 "Margin" user)
		(31 "F.CrtYd" user "Package Geometry/Place Bound Top")
		(29 "B.CrtYd" user "Package Geometry/Place Bound Bottom")
		(35 "F.Fab" user "Ref Des/Assembly Top")
		(33 "B.Fab" user "Ref Des/Assembly Bottom")
	)
	(footprint ""
		(layer "B.Cu")
		(at 403.947122 -416.899344 90)
		(property "Reference" "C6617"
			(at 0 0 90)
			(layer "B.SilkS")
			(hide yes)
			(effects
				(font
					(size 1.27 1.27)
				)
				(justify mirror)
			)
		)
		(property "Value" ""
			(at 0 0 90)
			(layer "B.Fab")
			(effects
				(font
					(size 1.27 1.27)
				)
				(justify mirror)
			)
		)
		(duplicate_pad_numbers_are_jumpers no)
		(fp_line
			(start 0.299974 -0.150114)
			(end -0.299974 -0.150114)
			(stroke
				(width 0.1)
				(type default)
			)
			(layer "B.Fab")
		)
		(fp_line
			(start -0.299974 -0.150114)
			(end -0.299974 0.150114)
			(stroke
				(width 0.1)
				(type default)
			)
			(layer "B.Fab")
		)
		(fp_line
			(start 0.299974 0.150114)
			(end 0.299974 -0.150114)
			(stroke
				(width 0.1)
				(type default)
			)
			(layer "B.Fab")
		)
		(fp_line
			(start -0.299974 0.150114)
			(end 0.299974 0.150114)
			(stroke
				(width 0.1)
				(type default)
			)
			(layer "B.Fab")
		)
		(pad "1" smd rect
			(at 0.2667 0 270)
			(size 0.3048 0.381)
			(layers "B.Cu" "B.Mask" "B.Paste")
			(net "P5E_CPU0_P3_TX_BUF_C_DP<10>")
		)
		(pad "2" smd rect
			(at -0.2667 0 270)
			(size 0.3048 0.381)
			(layers "B.Cu" "B.Mask" "B.Paste")
			(net "P5E_CPU0_P3_TX_BUF_DP<10>")
		)
	)
	(footprint ""
		(layer "B.Cu")
		(at 498.693948 -147.924266 90)
		(property "Reference" "X28"
			(at 0.956564 2.769362 270)
			(unlocked yes)
			(layer "B.SilkS")
			(effects
				(font
					(size 0.7874 0.5842)
					(thickness 0.1524)
				)
				(justify left mirror)
			)
		)
		(property "Value" ""
			(at 0 0 90)
			(layer "B.Fab")
			(effects
				(font
					(size 1.27 1.27)
				)
				(justify mirror)
			)
		)
		(property "Device Type" "TP_TDR_4P_FTS_TH-TP_TDR_4P_DIP,EMPTY,TP15"
			(at -1.30175 1.27 0)
			(unlocked yes)
			(layer "B.Fab")
			(hide yes)
			(effects
				(font
					(size 0.635 0.4064)
					(thickness 0.1524)
				)
				(justify mirror)
			)
		)
		(property "User Part Number" "N_A"
			(at -1.30175 1.27 0)
			(unlocked yes)
			(layer "Cmts.User")
			(hide yes)
			(effects
				(font
					(size 0.635 0.4064)
					(thickness 0.1524)
				)
				(justify mirror)
			)
		)
		(duplicate_pad_numbers_are_jumpers no)
		(fp_line
			(start 0 -1.27)
			(end 0 -0.635)
			(stroke
				(width 0.1524)
				(type default)
			)
			(layer "B.SilkS")
		)
		(fp_line
			(start -2.54 -1.27)
			(end 0 -1.27)
			(stroke
				(width 0.1524)
				(type default)
			)
			(layer "B.SilkS")
		)
		(fp_line
			(start -2.54 -1.1303)
			(end -2.54 -1.27)
			(stroke
				(width 0.1524)
				(type default)
			)
			(layer "B.SilkS")
		)
		(fp_line
			(start 0 0.635)
			(end 0 1.905)
			(stroke
				(width 0.1524)
				(type default)
			)
			(layer "B.SilkS")
		)
		(fp_line
			(start -2.54 1.4097)
			(end -2.54 1.1303)
			(stroke
				(width 0.1524)
				(type default)
			)
			(layer "B.SilkS")
		)
		(fp_line
			(start 0 3.175)
			(end 0 3.81)
			(stroke
				(width 0.1524)
				(type default)
			)
			(layer "B.SilkS")
		)
		(fp_line
			(start 0 3.81)
			(end -2.54 3.81)
			(stroke
				(width 0.1524)
				(type default)
			)
			(layer "B.SilkS")
		)
		(fp_line
			(start -2.54 3.81)
			(end -2.54 3.6703)
			(stroke
				(width 0.1524)
				(type default)
			)
			(layer "B.SilkS")
		)
		(fp_poly
			(pts
				(xy 2.285746 -0.762) (xy 2.285746 0.762) (xy 0.761746 0)
			)
			(stroke
				(width 0)
				(type default)
			)
			(fill yes)
			(layer "B.SilkS")
		)
		(fp_line
			(start 0 -1.27)
			(end 0 3.81)
			(stroke
				(width 0.1)
				(type default)
			)
			(layer "B.Fab")
		)
		(fp_line
			(start -2.54 -1.27)
			(end 0 -1.27)
			(stroke
				(width 0.1)
				(type default)
			)
			(layer "B.Fab")
		)
		(fp_line
			(start 0 3.81)
			(end -2.54 3.81)
			(stroke
				(width 0.1)
				(type default)
			)
			(layer "B.Fab")
		)
		(fp_line
			(start -2.54 3.81)
			(end -2.54 -1.27)
			(stroke
				(width 0.1)
				(type default)
			)
			(layer "B.Fab")
		)
		(fp_poly
			(pts
				(xy 0.761746 0) (xy 2.285746 -0.762) (xy 2.285746 0.762)
			)
			(stroke
				(width 0)
				(type default)
			)
			(fill yes)
			(layer "B.Fab")
		)
		(pad "1" thru_hole circle
			(at 0 0 270)
			(size 1.0033 1.0033)
			(drill 0.249936)
			(layers "*.Cu" "*.Mask")
			(remove_unused_layers no)
			(net "TDR_DIFF_80_IN6_DN")
			(clearance 0.10795)
			(padstack
				(mode front_inner_back)
				(layer "Inner"
					(shape circle)
					(size 0.8001 0.8001)
					(clearance 0.1524)
				)
				(layer "B.Cu"
					(shape circle)
					(size 1.0033 1.0033)
					(thermal_gap 0.10795)
					(clearance 0.10795)
				)
			)
		)
		(pad "2" thru_hole circle
			(at -2.54 0 270)
			(size 1.9939 1.9939)
			(drill 0.249936)
			(layers "*.Cu" "*.Mask")
			(remove_unused_layers no)
			(net "T1_GND")
			(clearance 0.10795)
			(padstack
				(mode front_inner_back)
				(layer "Inner"
					(shape circle)
					(size 0.8001 0.8001)
					(clearance 0.1524)
				)
				(layer "B.Cu"
					(shape circle)
					(size 1.9939 1.9939)
					(thermal_gap 0.10795)
					(clearance 0.10795)
				)
			)
		)
		(pad "3" thru_hole circle
			(at -2.54 2.54 270)
			(size 1.9939 1.9939)
			(drill 0.249936)
			(layers "*.Cu" "*.Mask")
			(remove_unused_layers no)
			(net "T1_GND")
			(clearance 0.10795)
			(padstack
				(mode front_inner_back)
				(layer "Inner"
					(shape circle)
					(size 0.8001 0.8001)
					(clearance 0.1524)
				)
				(layer "B.Cu"
					(shape circle)
					(size 1.9939 1.9939)
					(thermal_gap 0.10795)
					(clearance 0.10795)
				)
			)
		)
		(pad "4" thru_hole circle
			(at 0 2.54 270)
			(size 1.0033 1.0033)
			(drill 0.249936)
			(layers "*.Cu" "*.Mask")
			(remove_unused_layers no)
			(net "TDR_DIFF_80_IN6_DP")
			(clearance 0.10795)
			(padstack
				(mode front_inner_back)
				(layer "Inner"
					(shape circle)
					(size 0.8001 0.8001)
					(clearance 0.1524)
				)
				(layer "B.Cu"
					(shape circle)
					(size 1.0033 1.0033)
					(thermal_gap 0.10795)
					(clearance 0.10795)
				)
			)
		)
	)
	(footprint ""
		(layer "B.Cu")
		(at 364.165896 -256.012188 -90)
		(property "Reference" "C2155"
			(at 0 0 90)
			(layer "B.SilkS")
			(hide yes)
			(effects
				(font
					(size 1.27 1.27)
				)
				(justify mirror)
			)
		)
		(property "Value" ""
			(at 0 0 90)
			(layer "B.Fab")
			(effects
				(font
					(size 1.27 1.27)
				)
				(justify mirror)
			)
		)
		(duplicate_pad_numbers_are_jumpers no)
		(fp_line
			(start -0.7874 0.4064)
			(end 0.7874 0.4064)
			(stroke
				(width 0.1524)
				(type default)
			)
			(layer "B.SilkS")
		)
		(fp_line
			(start 0.7874 0.4064)
			(end 0.7874 -0.4064)
			(stroke
				(width 0.1524)
				(type default)
			)
			(layer "B.SilkS")
		)
		(fp_line
			(start -0.7874 -0.4064)
			(end -0.7874 0.4064)
			(stroke
				(width 0.1524)
				(type default)
			)
			(layer "B.SilkS")
		)
		(fp_line
			(start 0.7874 -0.4064)
			(end -0.7874 -0.4064)
			(stroke
				(width 0.1524)
				(type default)
			)
			(layer "B.SilkS")
		)
		(fp_line
			(start -0.67945 0.3048)
			(end -0.120396 0.3048)
			(stroke
				(width 0.1)
				(type default)
			)
			(layer "B.Fab")
		)
		(fp_line
			(start -0.120396 0.3048)
			(end -0.120396 0.2794)
			(stroke
				(width 0.1)
				(type default)
			)
			(layer "B.Fab")
		)
		(fp_line
			(start 0.12065 0.3048)
			(end 0.67945 0.3048)
			(stroke
				(width 0.1)
				(type default)
			)
			(layer "B.Fab")
		)
		(fp_line
			(start 0.67945 0.3048)
			(end 0.67945 -0.305054)
			(stroke
				(width 0.1)
				(type default)
			)
			(layer "B.Fab")
		)
		(fp_line
			(start -0.120396 0.2794)
			(end 0.12065 0.2794)
			(stroke
				(width 0.1)
				(type default)
			)
			(layer "B.Fab")
		)
		(fp_line
			(start 0.12065 0.2794)
			(end 0.12065 0.3048)
			(stroke
				(width 0.1)
				(type default)
			)
			(layer "B.Fab")
		)
		(fp_line
			(start -0.12065 -0.2794)
			(end -0.12065 -0.3048)
			(stroke
				(width 0.1)
				(type default)
			)
			(layer "B.Fab")
		)
		(fp_line
			(start 0.12065 -0.2794)
			(end -0.12065 -0.2794)
			(stroke
				(width 0.1)
				(type default)
			)
			(layer "B.Fab")
		)
		(fp_line
			(start -0.67945 -0.3048)
			(end -0.67945 0.3048)
			(stroke
				(width 0.1)
				(type default)
			)
			(layer "B.Fab")
		)
		(fp_line
			(start -0.12065 -0.3048)
			(end -0.67945 -0.3048)
			(stroke
				(width 0.1)
				(type default)
			)
			(layer "B.Fab")
		)
		(fp_line
			(start 0.12065 -0.305054)
			(end 0.12065 -0.2794)
			(stroke
				(width 0.1)
				(type default)
			)
			(layer "B.Fab")
		)
		(fp_line
			(start 0.67945 -0.305054)
			(end 0.12065 -0.305054)
			(stroke
				(width 0.1)
				(type default)
			)
			(layer "B.Fab")
		)
		(pad "1" smd circle
			(at 0.40005 0 90)
			(size 0 0)
			(layers "B.Cu" "B.Mask" "B.Paste")
			(net "PVDDCR_SOC_P0")
		)
		(pad "2" smd circle
			(at -0.40005 0 90)
			(size 0 0)
			(layers "B.Cu" "B.Mask" "B.Paste")
			(net "GND")
		)
	)
	(footprint ""
		(layer "B.Cu")
		(at 113.17478 -408.618436 90)
		(property "Reference" "R695"
			(at 0 0 90)
			(layer "B.SilkS")
			(hide yes)
			(effects
				(font
					(size 1.27 1.27)
				)
				(justify mirror)
			)
		)
		(property "Value" ""
			(at 0 0 90)
			(layer "B.Fab")
			(effects
				(font
					(size 1.27 1.27)
				)
				(justify mirror)
			)
		)
		(duplicate_pad_numbers_are_jumpers no)
		(fp_line
			(start 0.32512 -0.175006)
			(end -0.32512 -0.175006)
			(stroke
				(width 0.1)
				(type default)
			)
			(layer "B.Fab")
		)
		(fp_line
			(start -0.32512 -0.175006)
			(end -0.32512 0.175006)
			(stroke
				(width 0.1)
				(type default)
			)
			(layer "B.Fab")
		)
		(fp_line
			(start 0.32512 0.175006)
			(end 0.32512 -0.175006)
			(stroke
				(width 0.1)
				(type default)
			)
			(layer "B.Fab")
		)
		(fp_line
			(start -0.32512 0.175006)
			(end 0.32512 0.175006)
			(stroke
				(width 0.1)
				(type default)
			)
			(layer "B.Fab")
		)
		(pad "1" smd rect
			(at 0.2667 0 270)
			(size 0.3048 0.381)
			(layers "B.Cu" "B.Mask" "B.Paste")
			(net "SMB_RT_CPU1_P3_ROM_MUX_1D_SCL")
		)
		(pad "2" smd rect
			(at -0.2667 0 90)
			(size 0.3048 0.381)
			(layers "B.Cu" "B.Mask" "B.Paste")
			(net "SMB_RT_CPU1_P3_ROM_MUX_1D_R_SCL")
		)
	)
	(footprint ""
		(layer "B.Cu")
		(at 291.52469 -194.893946 180)
		(property "Reference" "R1570"
			(at 0 0 0)
			(layer "B.SilkS")
			(hide yes)
			(effects
				(font
					(size 1.27 1.27)
				)
				(justify mirror)
			)
		)
		(property "Value" ""
			(at 0 0 0)
			(layer "B.Fab")
			(effects
				(font
					(size 1.27 1.27)
				)
				(justify mirror)
			)
		)
		(duplicate_pad_numbers_are_jumpers no)
		(fp_line
			(start 0.7874 0.4064)
			(end 0.7874 -0.4064)
			(stroke
				(width 0.1524)
				(type default)
			)
			(layer "B.SilkS")
		)
		(fp_line
			(start 0.7874 -0.4064)
			(end -0.7874 -0.4064)
			(stroke
				(width 0.1524)
				(type default)
			)
			(layer "B.SilkS")
		)
		(fp_line
			(start -0.7874 0.4064)
			(end 0.7874 0.4064)
			(stroke
				(width 0.1524)
				(type default)
			)
			(layer "B.SilkS")
		)
		(fp_line
			(start -0.7874 -0.4064)
			(end -0.7874 0.4064)
			(stroke
				(width 0.1524)
				(type default)
			)
			(layer "B.SilkS")
		)
		(fp_line
			(start 0.67945 0.3048)
			(end 0.67945 -0.305054)
			(stroke
				(width 0.1)
				(type default)
			)
			(layer "B.Fab")
		)
		(fp_line
			(start 0.67945 -0.305054)
			(end 0.12065 -0.305054)
			(stroke
				(width 0.1)
				(type default)
			)
			(layer "B.Fab")
		)
		(fp_line
			(start 0.12065 0.3048)
			(end 0.67945 0.3048)
			(stroke
				(width 0.1)
				(type default)
			)
			(layer "B.Fab")
		)
		(fp_line
			(start 0.12065 0.2794)
			(end 0.12065 0.3048)
			(stroke
				(width 0.1)
				(type default)
			)
			(layer "B.Fab")
		)
		(fp_line
			(start 0.12065 -0.2794)
			(end -0.12065 -0.2794)
			(stroke
				(width 0.1)
				(type default)
			)
			(layer "B.Fab")
		)
		(fp_line
			(start 0.12065 -0.305054)
			(end 0.12065 -0.2794)
			(stroke
				(width 0.1)
				(type default)
			)
			(layer "B.Fab")
		)
		(fp_line
			(start -0.120396 0.3048)
			(end -0.120396 0.2794)
			(stroke
				(width 0.1)
				(type default)
			)
			(layer "B.Fab")
		)
		(fp_line
			(start -0.120396 0.2794)
			(end 0.12065 0.2794)
			(stroke
				(width 0.1)
				(type default)
			)
			(layer "B.Fab")
		)
		(fp_line
			(start -0.12065 -0.2794)
			(end -0.12065 -0.3048)
			(stroke
				(width 0.1)
				(type default)
			)
			(layer "B.Fab")
		)
		(fp_line
			(start -0.12065 -0.3048)
			(end -0.67945 -0.3048)
			(stroke
				(width 0.1)
				(type default)
			)
			(layer "B.Fab")
		)
		(fp_line
			(start -0.67945 0.3048)
			(end -0.120396 0.3048)
			(stroke
				(width 0.1)
				(type default)
			)
			(layer "B.Fab")
		)
		(fp_line
			(start -0.67945 -0.3048)
			(end -0.67945 0.3048)
			(stroke
				(width 0.1)
				(type default)
			)
			(layer "B.Fab")
		)
		(pad "1" smd circle
			(at 0.40005 0)
			(size 0 0)
			(layers "B.Cu" "B.Mask" "B.Paste")
			(net "I3C_SPD_DDRAF_CPU0_SCL")
		)
		(pad "2" smd circle
			(at -0.40005 0)
			(size 0 0)
			(layers "B.Cu" "B.Mask" "B.Paste")
			(net "I3C_SPD_DDRC_CPU0_SCL")
		)
	)
	(footprint ""
		(layer "B.Cu")
		(at 90.209878 -145.90141)
		(property "Reference" "C8246"
			(at 0 0 0)
			(layer "B.SilkS")
			(hide yes)
			(effects
				(font
					(size 1.27 1.27)
				)
				(justify mirror)
			)
		)
		(property "Value" ""
			(at 0 0 0)
			(layer "B.Fab")
			(effects
				(font
					(size 1.27 1.27)
				)
				(justify mirror)
			)
		)
		(duplicate_pad_numbers_are_jumpers no)
		(fp_line
			(start -0.7874 -0.4064)
			(end -0.7874 0.4064)
			(stroke
				(width 0.1524)
				(type default)
			)
			(layer "B.SilkS")
		)
		(fp_line
			(start -0.7874 0.4064)
			(end 0.7874 0.4064)
			(stroke
				(width 0.1524)
				(type default)
			)
			(layer "B.SilkS")
		)
		(fp_line
			(start 0.7874 -0.4064)
			(end -0.7874 -0.4064)
			(stroke
				(width 0.1524)
				(type default)
			)
			(layer "B.SilkS")
		)
		(fp_line
			(start 0.7874 0.4064)
			(end 0.7874 -0.4064)
			(stroke
				(width 0.1524)
				(type default)
			)
			(layer "B.SilkS")
		)
		(fp_line
			(start -0.67945 -0.3048)
			(end -0.67945 0.3048)
			(stroke
				(width 0.1)
				(type default)
			)
			(layer "B.Fab")
		)
		(fp_line
			(start -0.67945 0.3048)
			(end -0.120396 0.3048)
			(stroke
				(width 0.1)
				(type default)
			)
			(layer "B.Fab")
		)
		(fp_line
			(start -0.12065 -0.3048)
			(end -0.67945 -0.3048)
			(stroke
				(width 0.1)
				(type default)
			)
			(layer "B.Fab")
		)
		(fp_line
			(start -0.12065 -0.2794)
			(end -0.12065 -0.3048)
			(stroke
				(width 0.1)
				(type default)
			)
			(layer "B.Fab")
		)
		(fp_line
			(start -0.120396 0.2794)
			(end 0.12065 0.2794)
			(stroke
				(width 0.1)
				(type default)
			)
			(layer "B.Fab")
		)
		(fp_line
			(start -0.120396 0.3048)
			(end -0.120396 0.2794)
			(stroke
				(width 0.1)
				(type default)
			)
			(layer "B.Fab")
		)
		(fp_line
			(start 0.12065 -0.305054)
			(end 0.12065 -0.2794)
			(stroke
				(width 0.1)
				(type default)
			)
			(layer "B.Fab")
		)
		(fp_line
			(start 0.12065 -0.2794)
			(end -0.12065 -0.2794)
			(stroke
				(width 0.1)
				(type default)
			)
			(layer "B.Fab")
		)
		(fp_line
			(start 0.12065 0.2794)
			(end 0.12065 0.3048)
			(stroke
				(width 0.1)
				(type default)
			)
			(layer "B.Fab")
		)
		(fp_line
			(start 0.12065 0.3048)
			(end 0.67945 0.3048)
			(stroke
				(width 0.1)
				(type default)
			)
			(layer "B.Fab")
		)
		(fp_line
			(start 0.67945 -0.305054)
			(end 0.12065 -0.305054)
			(stroke
				(width 0.1)
				(type default)
			)
			(layer "B.Fab")
		)
		(fp_line
			(start 0.67945 0.3048)
			(end 0.67945 -0.305054)
			(stroke
				(width 0.1)
				(type default)
			)
			(layer "B.Fab")
		)
		(pad "1" smd circle
			(at 0.40005 0 180)
			(size 0 0)
			(layers "B.Cu" "B.Mask" "B.Paste")
			(net "PWRGD_PVDDCR_SOC_P1_R")
		)
		(pad "2" smd circle
			(at -0.40005 0 180)
			(size 0 0)
			(layers "B.Cu" "B.Mask" "B.Paste")
			(net "GND")
		)
	)
)
